FILE_TYPE = MULTI_PHYS_TABLE;

PART 'Q_DIODE'

{========================================================================================}
:VALUE           | PACK_TYPE | MATERIAL | PART_NUMBER        = STANDARD        | LIFECYCLE      | PART_NUMBER   | JEDEC_TYPE        | CLASS | DESCRIPTION                                | COMPONENT_TYPE | LEAD_LENGTH | LPID | DAY        ;
{========================================================================================}
 'CH751H-40PT'   | 'SMLF'    | 'IC'     | 'TMP_QBC000751Z05'(!) = 'End of Design' | 'End of Life'  | 'BC000751Z05' |'SOD323_EOL'| 'IC'  | 'DIODE SMD CH751H-40PT(40V,30MA)'          | 'SMALLSMT'     | ''          | ''   | ''        
 'CH751H-40PT'   | 'SMLF'    | 'EMPTY'  | 'TMP_QBC000751Z05'(!) = 'End of Design' | 'End of Life'  | 'BC000751Z05' |'SOD323_EOL'| 'IO'  | 'DIODE SMD CH751H-40PT(40V,30MA)'          | 'SMALLSMT'     | ''          | ''   | ''        
 '1N4448WS-7-F'  | 'SMLF'    | 'IC'     | 'TMP_QBC004448Z64'(!) = 'End of Design' | 'Comp-Approve' | 'BC004448Z64' |'SOD323'| 'IC'  | 'DIODE SMD 1N4448WS-7-F(100V,250MA)SOD323' | 'SMALLSMT'     | ''          | ''   | ''        
 '1N4448WS-7-F'  | 'SMLF'    | 'EMPTY'  | 'TMP_QBC004448Z64'(!) = 'End of Design' | 'Comp-Approve' | 'BC004448Z64' |'SOD323'| 'IO'  | 'DIODE SMD 1N4448WS-7-F(100V,250MA)SOD323' | 'SMALLSMT'     | ''          | ''   | ''        
 '1N4148WS-7-F'  | 'SMLF'    | 'IC'     | 'TMP_QBC004148Z79'(!) = ''              | ''             | 'BC004148Z79' |'SOD323'| 'IC'  | 'DIODE SMD 1N4148WS-7-F(75V,150MA)'        | 'SMALLSMT'     | ''          | ''   | ''        
 '1N4148WS-7-F'  | 'SMLF'    | 'EMPTY'  | 'TMP_QBC004148Z79'(!) = ''              | ''             | 'BC004148Z79' |'SOD323'| 'IO'  | 'DIODE SMD 1N4148WS-7-F(75V,150MA)'        | 'SMALLSMT'     | ''          | ''   | ''        
 'SL42-E3/57T'   | 'SMLF'    | 'IC'     | 'BC00SL42Z00'(!)   = ''              | 'End of Life'  | 'BC00SL42Z00' |'D2723_SMCXB_EOL'| 'IC'  | 'DIODE SMD SL42-E3/57T(20V,4A)SMC'         | 'SMALLSMT'     | ''          | ''   | ''        
 'SL42-E3/57T'   | 'SMLF'    | 'EMPTY'  | 'BC00SL42Z00'(!)   = ''              | 'End of Life'  | 'BC00SL42Z00' |'D2723_SMCXB_EOL'| 'IO'  | 'DIODE SMD SL42-E3/57T(20V,4A)SMC'         | 'SMALLSMT'     | ''          | ''   | ''        
 'SDMK0340L-7-F' | 'SMLF'    | 'IC'     | 'BC000340033'(!)   = ''              | ''             | 'BC000340033' |'SOD323XB'| 'IC'  | 'DIODE SMD SDMK0340L-7-F(40V,30MA)'        | 'SMALLSMT'     | ''          | ''   | '20101005'
 'SDMK0340L-7-F' | 'SMLF'    | 'EMPTY'  | 'BC000340033'(!)   = ''              | ''             | 'BC000340033' |'SOD323XB'| 'IO'  | 'DIODE SMD SDMK0340L-7-F(40V,30MA)'        | 'SMALLSMT'     | ''          | ''   | '20101005'
 'RB751V-40'     | 'SMLF'    | 'IC'     | 'BCRB751VZ16'(!)   = 'End of Design' | 'Comp-Approve' | 'BCRB751VZ16' |'SOD323'| 'IC'  | 'DIODE SMD RB751V-40(40V,30MA)'            | 'SMALLSMT'     | ''          | ''   | '20101123'
 'RB751V-40'     | 'SMLF'    | 'EMPTY'  | 'BCRB751VZ16'(!)   = 'End of Design' | 'Comp-Approve' | 'BCRB751VZ16' |'SOD323'| 'IO'  | 'DIODE SMD RB751V-40(40V,30MA)'            | 'SMALLSMT'     | ''          | ''   | '20101123'
 'BAS20HT1G'     | 'SMLF'    | 'IC'     | 'BC20HT1GZ00'(!)   = 'End of Design' | 'Comp-Approve' | 'BC20HT1GZ00' |'SOD323XG'| 'IC'  | 'DIODE SMD BAS20HT1G(200V,200MA)'          | 'SMALLSMT'     | ''          | ''   | '20130110'
 'BAS20HT1G'     | 'SMLF'    | 'EMPTY'  | 'BC20HT1GZ00'(!)   = 'End of Design' | 'Comp-Approve' | 'BC20HT1GZ00' |'SOD323XG'| 'IO'  | 'DIODE SMD BAS20HT1G(200V,200MA)'          | 'SMALLSMT'     | ''          | ''   | '20130110'
 '1N4148W-7-F'   | 'SMLF'    | 'IC'     | 'BC004148ZA0'(!)   = ''              | ''             | 'BC004148ZA0' |'SOD123'| 'IC'  | 'DIODE 1N4148W-7-F(75V.150MA)'             | 'SMALLSMT'     | ''          | ''   | '20140708'
 '1N4148W-7-F'   | 'SMLF'    | 'EMPTY'  | 'BC004148ZA0'(!)   = ''              | ''             | 'BC004148ZA0' |'SOD123'| 'IO'  | 'DIODE 1N4148W-7-F(75V.150MA)'             | 'SMALLSMT'     | ''          | ''   | '20140708'
 'BAV21W-7-F'    | 'SMLF'    | 'IC'     | 'BC00021WZ00'(!)   = ''              | ''             | 'BC00021WZ00' |'SOD123XC'| 'IC'  | 'DIODE SMD BAV21W-7-F(250V,0.4A)SOD-123'   | 'SMALLSMT'     | ''          | ''   | '20140801'
 'BAV21W-7-F'    | 'SMLF'    | 'EMPTY'  | 'BC00021WZ00'(!)   = ''              | ''             | 'BC00021WZ00' |'SOD123XC'| 'IO'  | 'DIODE SMD BAV21W-7-F(250V,0.4A)SOD-123'   | 'SMALLSMT'     | ''          | ''   | '20140801'
 'MMBD4148TS'    | 'SMLF'    | 'IC'     | 'BCBD4148Z03'(!)   = ''              | ''             | 'BCBD4148Z03' |'SOD523XE'| 'IC'  | 'DIODE SMD MMBD4148TS(75V,150MA)SOD523'    | 'SMALLSMT'     | ''          | ''   | '20150107'
 'MMBD4148TS'    | 'SMLF'    | 'EMPTY'  | 'BCBD4148Z03'(!)   = ''              | ''             | 'BCBD4148Z03' |'SOD523XE'| 'IO'  | 'DIODE SMD MMBD4148TS(75V,150MA)SOD523'    | 'SMALLSMT'     | ''          | ''   | '20150107'

END_PART

END.

